FILE_TYPE = CONNECTIVITY;
{Allegro Design Entry HDL 17.4-2019 S026 (4007227) 1/17/2022}
"PAGE_NUMBER" = 15;
0"NC";
1"M_F_CPU0_SA_DQ<31:0>";
2"M_F_CPU0_SB_DQ<31:0>";
3"M_F_CPU0_SA_CB<7:0>";
4"M_F_CPU0_SB_CB<7:0>";
5"M_F_CPU0_SA_DQS_DP<9:0>";
6"M_F_CPU0_SA_DQS_DN<9:0>";
7"M_F_CPU0_SB_DQS_DN<9:0>";
8"M_F_CPU0_SB_DQS_DP<9:0>";
9"M_F_CPU0_SA_CA<6:0>";
10"M_F_CPU0_SB_CA<6:0>";
11"M_F_CPU0_ALERT_N";
12"M_F_CPU0_ALERT_R_N";
13"TP_M_F_CPU0_SA_TEST39F";
14"M_F_CPU0_CLK_DP<0>";
15"M_F_CPU0_CLK_DN<0>";
16"M_F_CPU0_SA_CS_N<0>";
17"M_F_CPU0_SA_CS_N<1>";
18"M_F_CPU0_SB_RSP<0>";
19"M_F_CPU0_SA_RSP<0>";
20"M_F_CPU0_SA_PAR";
21"M_F_CPU0_SB_CS_N<0>";
22"M_F_CPU0_SB_CS_N<1>";
23"M_F_CPU0_SB_PAR";
24"M_F_CPU0_RESET_N";
25"M_F_CPU0_SB_DQS_DP<9>";
26"M_F_CPU0_SB_CA<6>";
27"M_F_CPU0_SA_CA<6>";
28"M_F_CPU0_SB_CA<5>";
29"M_F_CPU0_SA_CA<5>";
30"M_F_CPU0_SB_CA<4>";
31"M_F_CPU0_SA_CA<4>";
32"M_F_CPU0_SB_CA<3>";
33"M_F_CPU0_SA_CA<3>";
34"M_F_CPU0_SB_CA<2>";
35"M_F_CPU0_SA_CA<2>";
36"M_F_CPU0_SB_CA<1>";
37"M_F_CPU0_SA_CA<1>";
38"M_F_CPU0_SB_CA<0>";
39"M_F_CPU0_SA_CA<0>";
40"M_F_CPU0_SB_DQS_DN<9>";
41"M_F_CPU0_SB_DQS_DN<8>";
42"M_F_CPU0_SB_DQS_DP<1>";
43"M_F_CPU0_SB_DQS_DN<5>";
44"M_F_CPU0_SB_DQS_DP<0>";
45"M_F_CPU0_SB_DQS_DN<4>";
46"M_F_CPU0_SA_DQS_DN<9>";
47"M_F_CPU0_SB_DQS_DN<3>";
48"M_F_CPU0_SB_DQS_DN<2>";
49"M_F_CPU0_SB_DQS_DN<1>";
50"M_F_CPU0_SB_DQS_DN<0>";
51"M_F_CPU0_SB_DQS_DP<8>";
52"M_F_CPU0_SB_DQS_DP<7>";
53"M_F_CPU0_SB_DQS_DP<6>";
54"M_F_CPU0_SB_DQS_DP<5>";
55"M_F_CPU0_SB_DQS_DP<4>";
56"M_F_CPU0_SA_DQS_DP<9>";
57"M_F_CPU0_SB_DQS_DP<3>";
58"M_F_CPU0_SB_DQS_DN<7>";
59"M_F_CPU0_SB_DQS_DP<2>";
60"M_F_CPU0_SB_DQS_DN<6>";
61"M_F_CPU0_SA_DQS_DP<7>";
62"M_F_CPU0_SA_DQS_DP<6>";
63"M_F_CPU0_SA_DQS_DP<5>";
64"M_F_CPU0_SA_DQS_DP<4>";
65"M_F_CPU0_SA_DQS_DN<8>";
66"M_F_CPU0_SA_DQS_DP<3>";
67"M_F_CPU0_SA_DQS_DN<7>";
68"M_F_CPU0_SA_DQS_DP<2>";
69"M_F_CPU0_SA_DQS_DN<6>";
70"M_F_CPU0_SA_DQS_DP<1>";
71"M_F_CPU0_SA_DQS_DN<5>";
72"M_F_CPU0_SA_DQS_DP<0>";
73"M_F_CPU0_SA_DQS_DN<4>";
74"M_F_CPU0_SA_DQS_DN<3>";
75"M_F_CPU0_SA_DQS_DN<2>";
76"M_F_CPU0_SA_DQS_DN<1>";
77"M_F_CPU0_SA_DQS_DN<0>";
78"M_F_CPU0_SA_DQS_DP<8>";
79"M_F_CPU0_SB_CB<7>";
80"M_F_CPU0_SB_CB<6>";
81"M_F_CPU0_SB_CB<5>";
82"M_F_CPU0_SB_CB<4>";
83"M_F_CPU0_SB_CB<3>";
84"M_F_CPU0_SB_CB<2>";
85"M_F_CPU0_SA_CB<7>";
86"M_F_CPU0_SB_CB<1>";
87"M_F_CPU0_SB_CB<0>";
88"M_F_CPU0_SB_DQ<29>";
89"M_F_CPU0_SB_DQ<28>";
90"M_F_CPU0_SB_DQ<27>";
91"M_F_CPU0_SB_DQ<26>";
92"M_F_CPU0_SB_DQ<25>";
93"M_F_CPU0_SB_DQ<24>";
94"M_F_CPU0_SB_DQ<23>";
95"M_F_CPU0_SB_DQ<22>";
96"M_F_CPU0_SB_DQ<21>";
97"M_F_CPU0_SA_CB<6>";
98"M_F_CPU0_SB_DQ<31>";
99"M_F_CPU0_SA_CB<5>";
100"M_F_CPU0_SB_DQ<30>";
101"M_F_CPU0_SA_CB<4>";
102"M_F_CPU0_SA_CB<3>";
103"M_F_CPU0_SA_CB<2>";
104"M_F_CPU0_SA_CB<1>";
105"M_F_CPU0_SA_CB<0>";
106"M_F_CPU0_SB_DQ<6>";
107"M_F_CPU0_SB_DQ<18>";
108"M_F_CPU0_SB_DQ<5>";
109"M_F_CPU0_SB_DQ<17>";
110"M_F_CPU0_SB_DQ<4>";
111"M_F_CPU0_SB_DQ<16>";
112"M_F_CPU0_SB_DQ<3>";
113"M_F_CPU0_SB_DQ<15>";
114"M_F_CPU0_SB_DQ<2>";
115"M_F_CPU0_SB_DQ<14>";
116"M_F_CPU0_SB_DQ<13>";
117"M_F_CPU0_SB_DQ<12>";
118"M_F_CPU0_SB_DQ<11>";
119"M_F_CPU0_SB_DQ<10>";
120"M_F_CPU0_SB_DQ<20>";
121"M_F_CPU0_SB_DQ<9>";
122"M_F_CPU0_SB_DQ<8>";
123"M_F_CPU0_SB_DQ<7>";
124"M_F_CPU0_SB_DQ<19>";
125"M_F_CPU0_SA_DQ<19>";
126"M_F_CPU0_SB_DQ<1>";
127"M_F_CPU0_SA_DQ<18>";
128"M_F_CPU0_SA_DQ<29>";
129"M_F_CPU0_SB_DQ<0>";
130"M_F_CPU0_SA_DQ<17>";
131"M_F_CPU0_SA_DQ<28>";
132"M_F_CPU0_SA_DQ<16>";
133"M_F_CPU0_SA_DQ<27>";
134"M_F_CPU0_SA_DQ<26>";
135"M_F_CPU0_SA_DQ<25>";
136"M_F_CPU0_SA_DQ<24>";
137"M_F_CPU0_SA_DQ<23>";
138"M_F_CPU0_SA_DQ<22>";
139"M_F_CPU0_SA_DQ<21>";
140"M_F_CPU0_SA_DQ<20>";
141"M_F_CPU0_SA_DQ<31>";
142"M_F_CPU0_SA_DQ<30>";
143"M_F_CPU0_SA_DQ<7>";
144"M_F_CPU0_SA_DQ<6>";
145"M_F_CPU0_SA_DQ<5>";
146"M_F_CPU0_SA_DQ<4>";
147"M_F_CPU0_SA_DQ<3>";
148"M_F_CPU0_SA_DQ<2>";
149"M_F_CPU0_SA_DQ<1>";
150"M_F_CPU0_SA_DQ<0>";
151"M_F_CPU0_SA_DQ<15>";
152"M_F_CPU0_SA_DQ<14>";
153"M_F_CPU0_SA_DQ<13>";
154"M_F_CPU0_SA_DQ<12>";
155"M_F_CPU0_SA_DQ<11>";
156"M_F_CPU0_SA_DQ<10>";
157"M_F_CPU0_SA_DQ<9>";
158"M_F_CPU0_SA_DQ<8>";
%"GENOA_SP5"
"6","(-4650,3600)","0","pure_quanta","I159";
;
LOCATION"U25"
$SEC"6"
CDS_SEC"6"
PART_TYPE"SMLF"
MATERIAL"IO"
VALUE"SOCKET6096_13568-001"
CDS_LIB"pure_quanta"
CDS_LMAN_SYM_OUTLINE"-650,2525,650,-2525"
NEEDS_NO_SIZE"TRUE"
PART_NUMBER"DGA^6000030";
"TEST39F"
$PN"BF65"13;
"MF1_CLK_L"
$PN"BG67"0;
"MF1_CLK_H"
$PN"BF67"0;
"MF0_CLK_L"
$PN"BD67"15;
"MF0_CLK_H"
$PN"BC67"14;
"MFB_DQS_H9"
$PN"BV67"25;
"MFB_PAR"
$PN"BL67"23;
"MFA_PAR"
$PN"BC66"20;
"MFA0_CS_L0"
$PN"AV67"16;
"MFA_DATA7"
$PN"L66"143;
"MFA_DQS_H7"
$PN"AA66"61;
"MFB_DATA6"
$PN"CG67"106;
"MFB_DATA18"
$PN"CR67"107;
"MFB_DATA29"
$PN"DE66"88;
"MFB_DQS_H1"
$PN"CK67"42;
"MFB_DQS_L5"
$PN"CE66"43;
"MFA_DATA6"
$PN"K67"144;
"MFA_DQS_H6"
$PN"R66"62;
"MFB1_RSP_L"
$PN"BR67"0;
"MFB_DATA5"
$PN"CG66"108;
"MFB_DATA17"
$PN"CR66"109;
"MFB_DATA28"
$PN"DD67"89;
"MFB_DQS_H0"
$PN"CD67"44;
"MFB_DQS_L4"
$PN"BW66"45;
"MFA_DATA5"
$PN"K65"145;
"MFA_DQS_H5"
$PN"J66"63;
"MFA_DQS_L9"
$PN"AM65"46;
"MFB0_RSP_L"
$PN"BP67"18;
"MFB_CHECK7"
$PN"BV65"79;
"MFB_DATA4"
$PN"CF67"110;
"MFB_DATA16"
$PN"CP67"111;
"MFB_DATA27"
$PN"DB65"90;
"MFB_DQS_L3"
$PN"DC67"47;
"MFA_DATA4"
$PN"J67"146;
"MFA_DQS_H4"
$PN"AL67"64;
"MFA_DQS_L8"
$PN"AF65"65;
"MFB_CHECK6"
$PN"BU67"80;
"MFB_DATA3"
$PN"CD65"112;
"MFB_DATA15"
$PN"CP65"113;
"MFB_DATA26"
$PN"DA67"91;
"MFB_DQS_L2"
$PN"CU67"48;
"MFA_DATA3"
$PN"G66"147;
"MFA_DQS_H3"
$PN"AE67"66;
"MFA_DQS_L7"
$PN"Y65"67;
"MFB_CHECK5"
$PN"BU66"81;
"MFB_DATA2"
$PN"CC67"114;
"MFB_DATA14"
$PN"CN67"115;
"MFB_DATA25"
$PN"DA66"92;
"MFB_DQS_L1"
$PN"CL67"49;
"MFA_DATA2"
$PN"F67"148;
"MFA_DATA19"
$PN"W66"125;
"MFA_DQS_H2"
$PN"W67"68;
"MFA_DQS_L6"
$PN"P65"69;
"MFB_CA6"
$PN"BK67"26;
"MFB_CHECK4"
$PN"BT67"82;
"MFB_DATA1"
$PN"CC66"126;
"MFB_DATA13"
$PN"CN66"116;
"MFB_DATA24"
$PN"CY67"93;
"MFB_DQS_L0"
$PN"CE67"50;
"MFA_CA6"
$PN"BB65"27;
"MFA_DATA1"
$PN"F65"149;
"MFA_DATA18"
$PN"V67"127;
"MFA_DATA29"
$PN"AH65"128;
"MFA_DQS_H1"
$PN"N67"70;
"MFA_DQS_L5"
$PN"H65"71;
"MFB_CA5"
$PN"BK65"28;
"MFB_CHECK3"
$PN"CB65"83;
"MFB_DATA0"
$PN"CB67"129;
"MFB_DATA12"
$PN"CM67"117;
"MFB_DATA23"
$PN"CY65"94;
"MFA1_RSP_L"
$PN"BP65"0;
"MFA_CA5"
$PN"BB67"29;
"MFA_DATA0"
$PN"E67"150;
"MFA_DATA17"
$PN"V65"130;
"MFA_DATA28"
$PN"AG67"131;
"MFA_DQS_H0"
$PN"G67"72;
"MFA_DQS_L4"
$PN"AM67"73;
"MFB_CA4"
$PN"BJ66"30;
"MFB_CHECK2"
$PN"CA67"84;
"MFB_DATA11"
$PN"CK65"118;
"MFB_DATA22"
$PN"CW67"95;
"MFA0_RSP_L"
$PN"BN66"19;
"MFA_CA4"
$PN"BA67"31;
"MFA_CHECK7"
$PN"AR66"85;
"MFA_DATA16"
$PN"U67"132;
"MFA_DATA27"
$PN"AE66"133;
"MFA_DQS_L3"
$PN"AF67"74;
"MFB_CA3"
$PN"BJ67"32;
"MFB_CHECK1"
$PN"CA66"86;
"MFB_DATA10"
$PN"CJ67"119;
"MFB_DATA21"
$PN"CW66"96;
"MFA_CA3"
$PN"BA66"33;
"MFA_CHECK6"
$PN"AP67"97;
"MFA_DATA15"
$PN"U66"151;
"MFA_DATA26"
$PN"AD67"134;
"MFA_DQS_L2"
$PN"Y67"75;
"MFB1_CS_L1"
$PN"BM67"0;
"MFB_CA2"
$PN"BH67"34;
"MFB_CHECK0"
$PN"BY67"87;
"MFB_DATA20"
$PN"CV67"120;
"MFB_DATA31"
$PN"DF67"98;
"MFA_CA2"
$PN"AY65"35;
"MFA_CHECK5"
$PN"AP65"99;
"MFA_DATA14"
$PN"T67"152;
"MFA_DATA25"
$PN"AD65"135;
"MFA_DQS_L1"
$PN"P67"76;
"MFB0_CS_L1"
$PN"BN67"22;
"MFB1_CS_L0"
$PN"BL66"0;
"MFB_CA1"
$PN"BH65"36;
"MFB_DATA30"
$PN"DE67"100;
"MFB_DQS_H8"
$PN"DD65"51;
"MFA_CA1"
$PN"AY67"37;
"MFA_CHECK4"
$PN"AN67"101;
"MFA_DATA13"
$PN"T65"153;
"MFA_DATA24"
$PN"AC67"136;
"MFA_DQS_L0"
$PN"H67"77;
"MFB0_CS_L0"
$PN"BM65"21;
"MFB_CA0"
$PN"BG66"38;
"MFB_DQS_H7"
$PN"CV65"52;
"MFA_CA0"
$PN"AW67"39;
"MFA_CHECK3"
$PN"AL66"102;
"MFA_DATA12"
$PN"R67"154;
"MFA_DATA23"
$PN"AC66"137;
"MFB_DQS_H6"
$PN"CM65"53;
"MFA_CHECK2"
$PN"AK67"103;
"MFA_DATA11"
$PN"N66"155;
"MFA_DATA22"
$PN"AB67"138;
"MFB_DQS_H5"
$PN"CF65"54;
"MFB_DQS_L9"
$PN"BW67"40;
"MFA_CHECK1"
$PN"AK65"104;
"MFA_DATA10"
$PN"M67"156;
"MFA_DATA21"
$PN"AB65"139;
"MFB_DATA9"
$PN"CJ66"121;
"MFB_DQS_H4"
$PN"BY65"55;
"MFB_DQS_L8"
$PN"DC66"41;
"MFA1_CS_L1"
$PN"AV65"0;
"MFA_CHECK0"
$PN"AJ67"105;
"MFA_DATA9"
$PN"M65"157;
"MFA_DATA20"
$PN"AA67"140;
"MFA_DATA31"
$PN"AJ66"141;
"MFA_DQS_H9"
$PN"AN66"56;
"MFB_DATA8"
$PN"CH67"122;
"MFB_DQS_H3"
$PN"DB67"57;
"MFB_DQS_L7"
$PN"CU66"58;
"MFA0_CS_L1"
$PN"AW66"17;
"MFA1_CS_L0"
$PN"AU67"0;
"MFA_DATA8"
$PN"L67"158;
"MFA_DATA30"
$PN"AH67"142;
"MFA_DQS_H8"
$PN"AG66"78;
"MFB_DATA7"
$PN"CH65"123;
"MFB_DATA19"
$PN"CT65"124;
"MFB_DQS_H2"
$PN"CT67"59;
"MFB_DQS_L6"
$PN"CL66"60;
"MF_RESET_L"
$PN"AU66"24;
"MF_ALERT_L"
$PN"AT65"12;
%"TAP"
"1","(-3375,5975)","0","mstr_standard","I162";
;
CDS_LIB"mstr_standard"
BODY_TYPE"PLUMBING"
HDL_TAP"TRUE";
"B \NAC \NWC"1;
"S \NAC"
BN"0"150;
%"TAP"
"1","(-3375,5925)","0","mstr_standard","I163";
;
CDS_LIB"mstr_standard"
BODY_TYPE"PLUMBING"
HDL_TAP"TRUE";
"B \NAC \NWC"1;
"S \NAC"
BN"1"149;
%"TAP"
"1","(-3375,5775)","0","mstr_standard","I164";
;
CDS_LIB"mstr_standard"
BODY_TYPE"PLUMBING"
HDL_TAP"TRUE";
"B \NAC \NWC"1;
"S \NAC"
BN"4"146;
%"TAP"
"1","(-3375,5825)","0","mstr_standard","I165";
;
CDS_LIB"mstr_standard"
BODY_TYPE"PLUMBING"
HDL_TAP"TRUE";
"B \NAC \NWC"1;
"S \NAC"
BN"3"147;
%"TAP"
"1","(-3375,5875)","0","mstr_standard","I166";
;
CDS_LIB"mstr_standard"
BODY_TYPE"PLUMBING"
HDL_TAP"TRUE";
"B \NAC \NWC"1;
"S \NAC"
BN"2"148;
%"TAP"
"1","(-3375,5675)","0","mstr_standard","I167";
;
CDS_LIB"mstr_standard"
BODY_TYPE"PLUMBING"
HDL_TAP"TRUE";
"B \NAC \NWC"1;
"S \NAC"
BN"6"144;
%"TAP"
"1","(-3375,5725)","0","mstr_standard","I168";
;
CDS_LIB"mstr_standard"
BODY_TYPE"PLUMBING"
HDL_TAP"TRUE";
"B \NAC \NWC"1;
"S \NAC"
BN"5"145;
%"TAP"
"1","(-3375,5525)","0","mstr_standard","I169";
;
CDS_LIB"mstr_standard"
BODY_TYPE"PLUMBING"
HDL_TAP"TRUE";
"B \NAC \NWC"1;
"S \NAC"
BN"8"158;
%"TAP"
"1","(-3375,5625)","0","mstr_standard","I170";
;
CDS_LIB"mstr_standard"
BODY_TYPE"PLUMBING"
HDL_TAP"TRUE";
"B \NAC \NWC"1;
"S \NAC"
BN"7"143;
%"TAP"
"1","(-3375,5475)","0","mstr_standard","I171";
;
CDS_LIB"mstr_standard"
BODY_TYPE"PLUMBING"
HDL_TAP"TRUE";
"B \NAC \NWC"1;
"S \NAC"
BN"9"157;
%"TAP"
"1","(-3375,5425)","0","mstr_standard","I172";
;
CDS_LIB"mstr_standard"
BODY_TYPE"PLUMBING"
HDL_TAP"TRUE";
"B \NAC \NWC"1;
"S \NAC"
BN"10"156;
%"TAP"
"1","(-3375,5275)","0","mstr_standard","I173";
;
CDS_LIB"mstr_standard"
BODY_TYPE"PLUMBING"
HDL_TAP"TRUE";
"B \NAC \NWC"1;
"S \NAC"
BN"13"153;
%"TAP"
"1","(-3375,5325)","0","mstr_standard","I174";
;
CDS_LIB"mstr_standard"
BODY_TYPE"PLUMBING"
HDL_TAP"TRUE";
"B \NAC \NWC"1;
"S \NAC"
BN"12"154;
%"TAP"
"1","(-3375,5375)","0","mstr_standard","I175";
;
CDS_LIB"mstr_standard"
BODY_TYPE"PLUMBING"
HDL_TAP"TRUE";
"B \NAC \NWC"1;
"S \NAC"
BN"11"155;
%"TAP"
"1","(-3375,5175)","0","mstr_standard","I176";
;
CDS_LIB"mstr_standard"
BODY_TYPE"PLUMBING"
HDL_TAP"TRUE";
"B \NAC \NWC"1;
"S \NAC"
BN"15"151;
%"TAP"
"1","(-3375,5225)","0","mstr_standard","I177";
;
CDS_LIB"mstr_standard"
BODY_TYPE"PLUMBING"
HDL_TAP"TRUE";
"B \NAC \NWC"1;
"S \NAC"
BN"14"152;
%"TAP"
"1","(-3375,5025)","0","mstr_standard","I178";
;
CDS_LIB"mstr_standard"
BODY_TYPE"PLUMBING"
HDL_TAP"TRUE";
"B \NAC \NWC"1;
"S \NAC"
BN"17"130;
%"TAP"
"1","(-3375,5075)","0","mstr_standard","I179";
;
CDS_LIB"mstr_standard"
BODY_TYPE"PLUMBING"
HDL_TAP"TRUE";
"B \NAC \NWC"1;
"S \NAC"
BN"16"132;
%"TAP"
"1","(-3375,4875)","0","mstr_standard","I180";
;
CDS_LIB"mstr_standard"
BODY_TYPE"PLUMBING"
HDL_TAP"TRUE";
"B \NAC \NWC"1;
"S \NAC"
BN"20"140;
%"TAP"
"1","(-3375,4925)","0","mstr_standard","I181";
;
CDS_LIB"mstr_standard"
BODY_TYPE"PLUMBING"
HDL_TAP"TRUE";
"B \NAC \NWC"1;
"S \NAC"
BN"19"125;
%"TAP"
"1","(-3375,4975)","0","mstr_standard","I182";
;
CDS_LIB"mstr_standard"
BODY_TYPE"PLUMBING"
HDL_TAP"TRUE";
"B \NAC \NWC"1;
"S \NAC"
BN"18"127;
%"TAP"
"1","(-3375,4775)","0","mstr_standard","I183";
;
CDS_LIB"mstr_standard"
BODY_TYPE"PLUMBING"
HDL_TAP"TRUE";
"B \NAC \NWC"1;
"S \NAC"
BN"22"138;
%"TAP"
"1","(-3375,4825)","0","mstr_standard","I184";
;
CDS_LIB"mstr_standard"
BODY_TYPE"PLUMBING"
HDL_TAP"TRUE";
"B \NAC \NWC"1;
"S \NAC"
BN"21"139;
%"TAP"
"1","(-3375,4725)","0","mstr_standard","I185";
;
CDS_LIB"mstr_standard"
BODY_TYPE"PLUMBING"
HDL_TAP"TRUE";
"B \NAC \NWC"1;
"S \NAC"
BN"23"137;
%"TAP"
"1","(-3375,4625)","0","mstr_standard","I186";
;
CDS_LIB"mstr_standard"
BODY_TYPE"PLUMBING"
HDL_TAP"TRUE";
"B \NAC \NWC"1;
"S \NAC"
BN"24"136;
%"TAP"
"1","(-3375,4575)","0","mstr_standard","I187";
;
CDS_LIB"mstr_standard"
BODY_TYPE"PLUMBING"
HDL_TAP"TRUE";
"B \NAC \NWC"1;
"S \NAC"
BN"25"135;
%"TAP"
"1","(-3375,4525)","0","mstr_standard","I188";
;
CDS_LIB"mstr_standard"
BODY_TYPE"PLUMBING"
HDL_TAP"TRUE";
"B \NAC \NWC"1;
"S \NAC"
BN"26"134;
%"TAP"
"1","(-3375,4375)","0","mstr_standard","I189";
;
CDS_LIB"mstr_standard"
BODY_TYPE"PLUMBING"
HDL_TAP"TRUE";
"B \NAC \NWC"1;
"S \NAC"
BN"29"128;
%"TAP"
"1","(-3375,4425)","0","mstr_standard","I190";
;
CDS_LIB"mstr_standard"
BODY_TYPE"PLUMBING"
HDL_TAP"TRUE";
"B \NAC \NWC"1;
"S \NAC"
BN"28"131;
%"TAP"
"1","(-3375,4475)","0","mstr_standard","I191";
;
CDS_LIB"mstr_standard"
BODY_TYPE"PLUMBING"
HDL_TAP"TRUE";
"B \NAC \NWC"1;
"S \NAC"
BN"27"133;
%"TAP"
"1","(-3375,4275)","0","mstr_standard","I192";
;
CDS_LIB"mstr_standard"
BODY_TYPE"PLUMBING"
HDL_TAP"TRUE";
"B \NAC \NWC"1;
"S \NAC"
BN"31"141;
%"TAP"
"1","(-3375,4325)","0","mstr_standard","I193";
;
CDS_LIB"mstr_standard"
BODY_TYPE"PLUMBING"
HDL_TAP"TRUE";
"B \NAC \NWC"1;
"S \NAC"
BN"30"142;
%"TAP"
"1","(-3375,4125)","0","mstr_standard","I194";
;
CDS_LIB"mstr_standard"
BODY_TYPE"PLUMBING"
HDL_TAP"TRUE";
"B \NAC \NWC"2;
"S \NAC"
BN"1"126;
%"TAP"
"1","(-3375,4175)","0","mstr_standard","I195";
;
CDS_LIB"mstr_standard"
BODY_TYPE"PLUMBING"
HDL_TAP"TRUE";
"B \NAC \NWC"2;
"S \NAC"
BN"0"129;
%"TAP"
"1","(-3375,3975)","0","mstr_standard","I197";
;
CDS_LIB"mstr_standard"
BODY_TYPE"PLUMBING"
HDL_TAP"TRUE";
"B \NAC \NWC"2;
"S \NAC"
BN"4"110;
%"TAP"
"1","(-3375,4025)","0","mstr_standard","I198";
;
CDS_LIB"mstr_standard"
BODY_TYPE"PLUMBING"
HDL_TAP"TRUE";
"B \NAC \NWC"2;
"S \NAC"
BN"3"112;
%"TAP"
"1","(-3375,4075)","0","mstr_standard","I199";
;
CDS_LIB"mstr_standard"
BODY_TYPE"PLUMBING"
HDL_TAP"TRUE";
"B \NAC \NWC"2;
"S \NAC"
BN"2"114;
%"TAP"
"1","(-3375,3875)","0","mstr_standard","I200";
;
CDS_LIB"mstr_standard"
BODY_TYPE"PLUMBING"
HDL_TAP"TRUE";
"B \NAC \NWC"2;
"S \NAC"
BN"6"106;
%"TAP"
"1","(-3375,3925)","0","mstr_standard","I201";
;
CDS_LIB"mstr_standard"
BODY_TYPE"PLUMBING"
HDL_TAP"TRUE";
"B \NAC \NWC"2;
"S \NAC"
BN"5"108;
%"TAP"
"1","(-3375,3725)","0","mstr_standard","I202";
;
CDS_LIB"mstr_standard"
BODY_TYPE"PLUMBING"
HDL_TAP"TRUE";
"B \NAC \NWC"2;
"S \NAC"
BN"8"122;
%"TAP"
"1","(-3375,3825)","0","mstr_standard","I203";
;
CDS_LIB"mstr_standard"
BODY_TYPE"PLUMBING"
HDL_TAP"TRUE";
"B \NAC \NWC"2;
"S \NAC"
BN"7"123;
%"TAP"
"1","(-3375,3625)","0","mstr_standard","I204";
;
CDS_LIB"mstr_standard"
BODY_TYPE"PLUMBING"
HDL_TAP"TRUE";
"B \NAC \NWC"2;
"S \NAC"
BN"10"119;
%"TAP"
"1","(-3375,3675)","0","mstr_standard","I205";
;
CDS_LIB"mstr_standard"
BODY_TYPE"PLUMBING"
HDL_TAP"TRUE";
"B \NAC \NWC"2;
"S \NAC"
BN"9"121;
%"TAP"
"1","(-3375,3475)","0","mstr_standard","I206";
;
CDS_LIB"mstr_standard"
BODY_TYPE"PLUMBING"
HDL_TAP"TRUE";
"B \NAC \NWC"2;
"S \NAC"
BN"13"116;
%"TAP"
"1","(-3375,3525)","0","mstr_standard","I207";
;
CDS_LIB"mstr_standard"
BODY_TYPE"PLUMBING"
HDL_TAP"TRUE";
"B \NAC \NWC"2;
"S \NAC"
BN"12"117;
%"TAP"
"1","(-3375,3575)","0","mstr_standard","I208";
;
CDS_LIB"mstr_standard"
BODY_TYPE"PLUMBING"
HDL_TAP"TRUE";
"B \NAC \NWC"2;
"S \NAC"
BN"11"118;
%"TAP"
"1","(-3375,3425)","0","mstr_standard","I209";
;
CDS_LIB"mstr_standard"
BODY_TYPE"PLUMBING"
HDL_TAP"TRUE";
"B \NAC \NWC"2;
"S \NAC"
BN"14"115;
%"TAP"
"1","(-3375,3375)","0","mstr_standard","I210";
;
CDS_LIB"mstr_standard"
BODY_TYPE"PLUMBING"
HDL_TAP"TRUE";
"B \NAC \NWC"2;
"S \NAC"
BN"15"113;
%"TAP"
"1","(-3375,3275)","0","mstr_standard","I211";
;
CDS_LIB"mstr_standard"
BODY_TYPE"PLUMBING"
HDL_TAP"TRUE";
"B \NAC \NWC"2;
"S \NAC"
BN"16"111;
%"TAP"
"1","(-3375,3225)","0","mstr_standard","I212";
;
CDS_LIB"mstr_standard"
BODY_TYPE"PLUMBING"
HDL_TAP"TRUE";
"B \NAC \NWC"2;
"S \NAC"
BN"17"109;
%"TAP"
"1","(-3375,3075)","0","mstr_standard","I213";
;
CDS_LIB"mstr_standard"
BODY_TYPE"PLUMBING"
HDL_TAP"TRUE";
"B \NAC \NWC"2;
"S \NAC"
BN"20"120;
%"TAP"
"1","(-3375,3125)","0","mstr_standard","I214";
;
CDS_LIB"mstr_standard"
BODY_TYPE"PLUMBING"
HDL_TAP"TRUE";
"B \NAC \NWC"2;
"S \NAC"
BN"19"124;
%"TAP"
"1","(-3375,3175)","0","mstr_standard","I215";
;
CDS_LIB"mstr_standard"
BODY_TYPE"PLUMBING"
HDL_TAP"TRUE";
"B \NAC \NWC"2;
"S \NAC"
BN"18"107;
%"TAP"
"1","(-3375,2975)","0","mstr_standard","I216";
;
CDS_LIB"mstr_standard"
BODY_TYPE"PLUMBING"
HDL_TAP"TRUE";
"B \NAC \NWC"2;
"S \NAC"
BN"22"95;
%"TAP"
"1","(-3375,3025)","0","mstr_standard","I217";
;
CDS_LIB"mstr_standard"
BODY_TYPE"PLUMBING"
HDL_TAP"TRUE";
"B \NAC \NWC"2;
"S \NAC"
BN"21"96;
%"TAP"
"1","(-3375,2825)","0","mstr_standard","I218";
;
CDS_LIB"mstr_standard"
BODY_TYPE"PLUMBING"
HDL_TAP"TRUE";
"B \NAC \NWC"2;
"S \NAC"
BN"24"93;
%"TAP"
"1","(-3375,2925)","0","mstr_standard","I219";
;
CDS_LIB"mstr_standard"
BODY_TYPE"PLUMBING"
HDL_TAP"TRUE";
"B \NAC \NWC"2;
"S \NAC"
BN"23"94;
%"TAP"
"1","(-3375,2775)","0","mstr_standard","I220";
;
CDS_LIB"mstr_standard"
BODY_TYPE"PLUMBING"
HDL_TAP"TRUE";
"B \NAC \NWC"2;
"S \NAC"
BN"25"92;
%"TAP"
"1","(-3375,2725)","0","mstr_standard","I221";
;
CDS_LIB"mstr_standard"
BODY_TYPE"PLUMBING"
HDL_TAP"TRUE";
"B \NAC \NWC"2;
"S \NAC"
BN"26"91;
%"TAP"
"1","(-3375,2575)","0","mstr_standard","I222";
;
CDS_LIB"mstr_standard"
BODY_TYPE"PLUMBING"
HDL_TAP"TRUE";
"B \NAC \NWC"2;
"S \NAC"
BN"29"88;
%"TAP"
"1","(-3375,2625)","0","mstr_standard","I223";
;
CDS_LIB"mstr_standard"
BODY_TYPE"PLUMBING"
HDL_TAP"TRUE";
"B \NAC \NWC"2;
"S \NAC"
BN"28"89;
%"TAP"
"1","(-3375,2675)","0","mstr_standard","I224";
;
CDS_LIB"mstr_standard"
BODY_TYPE"PLUMBING"
HDL_TAP"TRUE";
"B \NAC \NWC"2;
"S \NAC"
BN"27"90;
%"TAP"
"1","(-3375,2525)","0","mstr_standard","I225";
;
CDS_LIB"mstr_standard"
BODY_TYPE"PLUMBING"
HDL_TAP"TRUE";
"B \NAC \NWC"2;
"S \NAC"
BN"30"100;
%"TAP"
"1","(-3375,2475)","0","mstr_standard","I226";
;
CDS_LIB"mstr_standard"
BODY_TYPE"PLUMBING"
HDL_TAP"TRUE";
"B \NAC \NWC"2;
"S \NAC"
BN"31"98;
%"TAP"
"1","(-3375,2325)","0","mstr_standard","I227";
;
CDS_LIB"mstr_standard"
BODY_TYPE"PLUMBING"
HDL_TAP"TRUE";
"B \NAC \NWC"3;
"S \NAC"
BN"1"104;
%"TAP"
"1","(-3375,2375)","0","mstr_standard","I228";
;
CDS_LIB"mstr_standard"
BODY_TYPE"PLUMBING"
HDL_TAP"TRUE";
"B \NAC \NWC"3;
"S \NAC"
BN"0"105;
%"TAP"
"1","(-3375,2275)","0","mstr_standard","I229";
;
CDS_LIB"mstr_standard"
BODY_TYPE"PLUMBING"
HDL_TAP"TRUE";
"B \NAC \NWC"3;
"S \NAC"
BN"2"103;
%"TAP"
"1","(-3375,2225)","0","mstr_standard","I230";
;
CDS_LIB"mstr_standard"
BODY_TYPE"PLUMBING"
HDL_TAP"TRUE";
"B \NAC \NWC"3;
"S \NAC"
BN"3"102;
%"TAP"
"1","(-3375,2075)","0","mstr_standard","I231";
;
CDS_LIB"mstr_standard"
BODY_TYPE"PLUMBING"
HDL_TAP"TRUE";
"B \NAC \NWC"3;
"S \NAC"
BN"6"97;
%"TAP"
"1","(-3375,2125)","0","mstr_standard","I232";
;
CDS_LIB"mstr_standard"
BODY_TYPE"PLUMBING"
HDL_TAP"TRUE";
"B \NAC \NWC"3;
"S \NAC"
BN"5"99;
%"TAP"
"1","(-3375,2175)","0","mstr_standard","I233";
;
CDS_LIB"mstr_standard"
BODY_TYPE"PLUMBING"
HDL_TAP"TRUE";
"B \NAC \NWC"3;
"S \NAC"
BN"4"101;
%"TAP"
"1","(-3375,2025)","0","mstr_standard","I235";
;
CDS_LIB"mstr_standard"
BODY_TYPE"PLUMBING"
HDL_TAP"TRUE";
"B \NAC \NWC"3;
"S \NAC"
BN"7"85;
%"TAP"
"1","(-3375,1925)","0","mstr_standard","I236";
;
CDS_LIB"mstr_standard"
BODY_TYPE"PLUMBING"
HDL_TAP"TRUE";
"B \NAC \NWC"4;
"S \NAC"
BN"0"87;
%"TAP"
"1","(-3375,1825)","0","mstr_standard","I237";
;
CDS_LIB"mstr_standard"
BODY_TYPE"PLUMBING"
HDL_TAP"TRUE";
"B \NAC \NWC"4;
"S \NAC"
BN"2"84;
%"TAP"
"1","(-3375,1875)","0","mstr_standard","I238";
;
CDS_LIB"mstr_standard"
BODY_TYPE"PLUMBING"
HDL_TAP"TRUE";
"B \NAC \NWC"4;
"S \NAC"
BN"1"86;
%"TAP"
"1","(-3375,1675)","0","mstr_standard","I239";
;
CDS_LIB"mstr_standard"
BODY_TYPE"PLUMBING"
HDL_TAP"TRUE";
"B \NAC \NWC"4;
"S \NAC"
BN"5"81;
%"TAP"
"1","(-3375,1725)","0","mstr_standard","I240";
;
CDS_LIB"mstr_standard"
BODY_TYPE"PLUMBING"
HDL_TAP"TRUE";
"B \NAC \NWC"4;
"S \NAC"
BN"4"82;
%"TAP"
"1","(-3375,1775)","0","mstr_standard","I241";
;
CDS_LIB"mstr_standard"
BODY_TYPE"PLUMBING"
HDL_TAP"TRUE";
"B \NAC \NWC"4;
"S \NAC"
BN"3"83;
%"TAP"
"1","(-3375,1575)","0","mstr_standard","I242";
;
CDS_LIB"mstr_standard"
BODY_TYPE"PLUMBING"
HDL_TAP"TRUE";
"B \NAC \NWC"4;
"S \NAC"
BN"7"79;
%"TAP"
"1","(-3375,1625)","0","mstr_standard","I243";
;
CDS_LIB"mstr_standard"
BODY_TYPE"PLUMBING"
HDL_TAP"TRUE";
"B \NAC \NWC"4;
"S \NAC"
BN"6"80;
%"TAP"
"1","(-5800,5975)","2","mstr_standard","I244";
;
CDS_LIB"mstr_standard"
BODY_TYPE"PLUMBING"
HDL_TAP"TRUE";
"B \NAC \NWC"5;
"S \NAC"
BN"0"72;
%"TAP"
"1","(-5800,5875)","2","mstr_standard","I245";
;
CDS_LIB"mstr_standard"
BODY_TYPE"PLUMBING"
HDL_TAP"TRUE";
"B \NAC \NWC"5;
"S \NAC"
BN"1"70;
%"TAP"
"1","(-5800,5775)","2","mstr_standard","I246";
;
CDS_LIB"mstr_standard"
BODY_TYPE"PLUMBING"
HDL_TAP"TRUE";
"B \NAC \NWC"5;
"S \NAC"
BN"2"68;
%"TAP"
"1","(-5800,5675)","2","mstr_standard","I247";
;
CDS_LIB"mstr_standard"
BODY_TYPE"PLUMBING"
HDL_TAP"TRUE";
"B \NAC \NWC"5;
"S \NAC"
BN"3"66;
%"TAP"
"1","(-6000,5925)","2","mstr_standard","I248";
;
CDS_LIB"mstr_standard"
BODY_TYPE"PLUMBING"
HDL_TAP"TRUE";
"B \NAC \NWC"6;
"S \NAC"
BN"0"77;
%"TAP"
"1","(-6000,5825)","2","mstr_standard","I249";
;
CDS_LIB"mstr_standard"
BODY_TYPE"PLUMBING"
HDL_TAP"TRUE";
"B \NAC \NWC"6;
"S \NAC"
BN"1"76;
%"TAP"
"1","(-6000,5725)","2","mstr_standard","I250";
;
CDS_LIB"mstr_standard"
BODY_TYPE"PLUMBING"
HDL_TAP"TRUE";
"B \NAC \NWC"6;
"S \NAC"
BN"2"75;
%"TAP"
"1","(-5800,5575)","2","mstr_standard","I251";
;
CDS_LIB"mstr_standard"
BODY_TYPE"PLUMBING"
HDL_TAP"TRUE";
"B \NAC \NWC"5;
"S \NAC"
BN"4"64;
%"TAP"
"1","(-5800,5475)","2","mstr_standard","I252";
;
CDS_LIB"mstr_standard"
BODY_TYPE"PLUMBING"
HDL_TAP"TRUE";
"B \NAC \NWC"5;
"S \NAC"
BN"5"63;
%"TAP"
"1","(-5800,5375)","2","mstr_standard","I253";
;
CDS_LIB"mstr_standard"
BODY_TYPE"PLUMBING"
HDL_TAP"TRUE";
"B \NAC \NWC"5;
"S \NAC"
BN"6"62;
%"TAP"
"1","(-5800,5275)","2","mstr_standard","I254";
;
CDS_LIB"mstr_standard"
BODY_TYPE"PLUMBING"
HDL_TAP"TRUE";
"B \NAC \NWC"5;
"S \NAC"
BN"7"61;
%"TAP"
"1","(-5800,5175)","2","mstr_standard","I255";
;
CDS_LIB"mstr_standard"
BODY_TYPE"PLUMBING"
HDL_TAP"TRUE";
"B \NAC \NWC"5;
"S \NAC"
BN"8"78;
%"TAP"
"1","(-6000,5625)","2","mstr_standard","I256";
;
CDS_LIB"mstr_standard"
BODY_TYPE"PLUMBING"
HDL_TAP"TRUE";
"B \NAC \NWC"6;
"S \NAC"
BN"3"74;
%"TAP"
"1","(-6000,5525)","2","mstr_standard","I257";
;
CDS_LIB"mstr_standard"
BODY_TYPE"PLUMBING"
HDL_TAP"TRUE";
"B \NAC \NWC"6;
"S \NAC"
BN"4"73;
%"TAP"
"1","(-6000,5425)","2","mstr_standard","I258";
;
CDS_LIB"mstr_standard"
BODY_TYPE"PLUMBING"
HDL_TAP"TRUE";
"B \NAC \NWC"6;
"S \NAC"
BN"5"71;
%"TAP"
"1","(-6000,5325)","2","mstr_standard","I259";
;
CDS_LIB"mstr_standard"
BODY_TYPE"PLUMBING"
HDL_TAP"TRUE";
"B \NAC \NWC"6;
"S \NAC"
BN"6"69;
%"TAP"
"1","(-6000,5125)","2","mstr_standard","I260";
;
CDS_LIB"mstr_standard"
BODY_TYPE"PLUMBING"
HDL_TAP"TRUE";
"B \NAC \NWC"6;
"S \NAC"
BN"8"65;
%"TAP"
"1","(-6000,5225)","2","mstr_standard","I261";
;
CDS_LIB"mstr_standard"
BODY_TYPE"PLUMBING"
HDL_TAP"TRUE";
"B \NAC \NWC"6;
"S \NAC"
BN"7"67;
%"TAP"
"1","(-5800,5075)","2","mstr_standard","I262";
;
CDS_LIB"mstr_standard"
BODY_TYPE"PLUMBING"
HDL_TAP"TRUE";
"B \NAC \NWC"5;
"S \NAC"
BN"9"56;
%"TAP"
"1","(-5800,4925)","2","mstr_standard","I263";
;
CDS_LIB"mstr_standard"
BODY_TYPE"PLUMBING"
HDL_TAP"TRUE";
"B \NAC \NWC"8;
"S \NAC"
BN"0"44;
%"TAP"
"1","(-5800,4825)","2","mstr_standard","I264";
;
CDS_LIB"mstr_standard"
BODY_TYPE"PLUMBING"
HDL_TAP"TRUE";
"B \NAC \NWC"8;
"S \NAC"
BN"1"42;
%"TAP"
"1","(-5800,4725)","2","mstr_standard","I265";
;
CDS_LIB"mstr_standard"
BODY_TYPE"PLUMBING"
HDL_TAP"TRUE";
"B \NAC \NWC"8;
"S \NAC"
BN"2"59;
%"TAP"
"1","(-5800,4625)","2","mstr_standard","I266";
;
CDS_LIB"mstr_standard"
BODY_TYPE"PLUMBING"
HDL_TAP"TRUE";
"B \NAC \NWC"8;
"S \NAC"
BN"3"57;
%"TAP"
"1","(-6000,5025)","2","mstr_standard","I267";
;
CDS_LIB"mstr_standard"
BODY_TYPE"PLUMBING"
HDL_TAP"TRUE";
"B \NAC \NWC"6;
"S \NAC"
BN"9"46;
%"TAP"
"1","(-6000,4875)","2","mstr_standard","I268";
;
CDS_LIB"mstr_standard"
BODY_TYPE"PLUMBING"
HDL_TAP"TRUE";
"B \NAC \NWC"7;
"S \NAC"
BN"0"50;
%"TAP"
"1","(-6000,4775)","2","mstr_standard","I269";
;
CDS_LIB"mstr_standard"
BODY_TYPE"PLUMBING"
HDL_TAP"TRUE";
"B \NAC \NWC"7;
"S \NAC"
BN"1"49;
%"TAP"
"1","(-6000,4675)","2","mstr_standard","I270";
;
CDS_LIB"mstr_standard"
BODY_TYPE"PLUMBING"
HDL_TAP"TRUE";
"B \NAC \NWC"7;
"S \NAC"
BN"2"48;
%"TAP"
"1","(-5800,4525)","2","mstr_standard","I271";
;
CDS_LIB"mstr_standard"
BODY_TYPE"PLUMBING"
HDL_TAP"TRUE";
"B \NAC \NWC"8;
"S \NAC"
BN"4"55;
%"TAP"
"1","(-5800,4425)","2","mstr_standard","I272";
;
CDS_LIB"mstr_standard"
BODY_TYPE"PLUMBING"
HDL_TAP"TRUE";
"B \NAC \NWC"8;
"S \NAC"
BN"5"54;
%"TAP"
"1","(-5800,4325)","2","mstr_standard","I273";
;
CDS_LIB"mstr_standard"
BODY_TYPE"PLUMBING"
HDL_TAP"TRUE";
"B \NAC \NWC"8;
"S \NAC"
BN"6"53;
%"TAP"
"1","(-5800,4225)","2","mstr_standard","I274";
;
CDS_LIB"mstr_standard"
BODY_TYPE"PLUMBING"
HDL_TAP"TRUE";
"B \NAC \NWC"8;
"S \NAC"
BN"7"52;
%"TAP"
"1","(-5800,4125)","2","mstr_standard","I275";
;
CDS_LIB"mstr_standard"
BODY_TYPE"PLUMBING"
HDL_TAP"TRUE";
"B \NAC \NWC"8;
"S \NAC"
BN"8"51;
%"TAP"
"1","(-6000,4575)","2","mstr_standard","I276";
;
CDS_LIB"mstr_standard"
BODY_TYPE"PLUMBING"
HDL_TAP"TRUE";
"B \NAC \NWC"7;
"S \NAC"
BN"3"47;
%"TAP"
"1","(-6000,4475)","2","mstr_standard","I277";
;
CDS_LIB"mstr_standard"
BODY_TYPE"PLUMBING"
HDL_TAP"TRUE";
"B \NAC \NWC"7;
"S \NAC"
BN"4"45;
%"TAP"
"1","(-6000,4375)","2","mstr_standard","I278";
;
CDS_LIB"mstr_standard"
BODY_TYPE"PLUMBING"
HDL_TAP"TRUE";
"B \NAC \NWC"7;
"S \NAC"
BN"5"43;
%"TAP"
"1","(-6000,4275)","2","mstr_standard","I279";
;
CDS_LIB"mstr_standard"
BODY_TYPE"PLUMBING"
HDL_TAP"TRUE";
"B \NAC \NWC"7;
"S \NAC"
BN"6"60;
%"TAP"
"1","(-6000,4175)","2","mstr_standard","I280";
;
CDS_LIB"mstr_standard"
BODY_TYPE"PLUMBING"
HDL_TAP"TRUE";
"B \NAC \NWC"7;
"S \NAC"
BN"7"58;
%"TAP"
"1","(-5800,4025)","2","mstr_standard","I285";
;
CDS_LIB"mstr_standard"
BODY_TYPE"PLUMBING"
HDL_TAP"TRUE";
"B \NAC \NWC"8;
"S \NAC"
BN"9"25;
%"TAP"
"1","(-6000,3975)","2","mstr_standard","I286";
;
CDS_LIB"mstr_standard"
BODY_TYPE"PLUMBING"
HDL_TAP"TRUE";
"B \NAC \NWC"7;
"S \NAC"
BN"9"40;
%"TAP"
"1","(-6000,4075)","2","mstr_standard","I287";
;
CDS_LIB"mstr_standard"
BODY_TYPE"PLUMBING"
HDL_TAP"TRUE";
"B \NAC \NWC"7;
"S \NAC"
BN"8"41;
%"TAP"
"1","(-6000,3825)","2","mstr_standard","I288";
;
CDS_LIB"mstr_standard"
BODY_TYPE"PLUMBING"
HDL_TAP"TRUE";
"B \NAC \NWC"9;
"S \NAC"
BN"0"39;
%"TAP"
"1","(-6000,3775)","2","mstr_standard","I289";
;
CDS_LIB"mstr_standard"
BODY_TYPE"PLUMBING"
HDL_TAP"TRUE";
"B \NAC \NWC"9;
"S \NAC"
BN"1"37;
%"TAP"
"1","(-6000,3725)","2","mstr_standard","I290";
;
CDS_LIB"mstr_standard"
BODY_TYPE"PLUMBING"
HDL_TAP"TRUE";
"B \NAC \NWC"9;
"S \NAC"
BN"2"35;
%"TAP"
"1","(-6000,3675)","2","mstr_standard","I291";
;
CDS_LIB"mstr_standard"
BODY_TYPE"PLUMBING"
HDL_TAP"TRUE";
"B \NAC \NWC"9;
"S \NAC"
BN"3"33;
%"TAP"
"1","(-6000,3625)","2","mstr_standard","I292";
;
CDS_LIB"mstr_standard"
BODY_TYPE"PLUMBING"
HDL_TAP"TRUE";
"B \NAC \NWC"9;
"S \NAC"
BN"4"31;
%"TAP"
"1","(-6000,3575)","2","mstr_standard","I293";
;
CDS_LIB"mstr_standard"
BODY_TYPE"PLUMBING"
HDL_TAP"TRUE";
"B \NAC \NWC"9;
"S \NAC"
BN"5"29;
%"TAP"
"1","(-6000,3525)","2","mstr_standard","I294";
;
CDS_LIB"mstr_standard"
BODY_TYPE"PLUMBING"
HDL_TAP"TRUE";
"B \NAC \NWC"9;
"S \NAC"
BN"6"27;
%"TAP"
"1","(-6000,3425)","2","mstr_standard","I295";
;
CDS_LIB"mstr_standard"
BODY_TYPE"PLUMBING"
HDL_TAP"TRUE";
"B \NAC \NWC"10;
"S \NAC"
BN"0"38;
%"TAP"
"1","(-6000,3375)","2","mstr_standard","I296";
;
CDS_LIB"mstr_standard"
BODY_TYPE"PLUMBING"
HDL_TAP"TRUE";
"B \NAC \NWC"10;
"S \NAC"
BN"1"36;
%"TAP"
"1","(-6000,3325)","2","mstr_standard","I297";
;
CDS_LIB"mstr_standard"
BODY_TYPE"PLUMBING"
HDL_TAP"TRUE";
"B \NAC \NWC"10;
"S \NAC"
BN"2"34;
%"TAP"
"1","(-6000,3275)","2","mstr_standard","I298";
;
CDS_LIB"mstr_standard"
BODY_TYPE"PLUMBING"
HDL_TAP"TRUE";
"B \NAC \NWC"10;
"S \NAC"
BN"3"32;
%"TAP"
"1","(-6000,3225)","2","mstr_standard","I299";
;
CDS_LIB"mstr_standard"
BODY_TYPE"PLUMBING"
HDL_TAP"TRUE";
"B \NAC \NWC"10;
"S \NAC"
BN"4"30;
%"TAP"
"1","(-6000,3125)","2","mstr_standard","I300";
;
CDS_LIB"mstr_standard"
BODY_TYPE"PLUMBING"
HDL_TAP"TRUE";
"B \NAC \NWC"10;
"S \NAC"
BN"6"26;
%"TAP"
"1","(-6000,3175)","2","mstr_standard","I301";
;
CDS_LIB"mstr_standard"
BODY_TYPE"PLUMBING"
HDL_TAP"TRUE";
"B \NAC \NWC"10;
"S \NAC"
BN"5"28;
%"Q_RES"
"1","(-6925,2125)","0","pure_quanta","I314";
;
LOCATION"R380"
$SEC"1"
CDS_SEC"1"
PACK_TYPE"0402LF"
TOLERANCE"1%"
VALUE"15"
MATERIAL"CHIP"
WATTAGE"1/16W"
CDS_LIB"pure_quanta"
PART_NUMBER"CS01502FB03";
"B"
$PN"2"12;
"A"
$PN"1"11;
END.
